# S9S_MB_2U (Grand Teton) — schematic netlist excerpt (pin names and nets, part order shuffled) for the footprints in the layout excerpt that follows; sources: Cadence DE-HDL packaged netlist, KiCad conversion of 03242023_DA0F0TMBIJ0_F0T_Motherboard_J_brd_V01_OCP.brd

J85  PICOPROBE_BXA  DELTA-L 4.0 EMPTY  pkg TRIANG_LAUNCH_3PXB  page 308
  \1_p\  = DELTA_L_85_10INCH_IN3_DN
  \2_n\  = DELTA_L_85_10INCH_IN3_DP
  \3_g\  = DELTA_L_GND_1

(kicad_pcb
	(version 20260206)
	(generator "pcbnew")
	(generator_version "10.0")
	(general
		(thickness 1.6)
		(legacy_teardrops no)
	)
	(paper "A4")
	(title_block
		(title "03242023_DA0F0TMBIJ0_F0T_Motherboard_J_brd_V01_OCP.brd")
		(comment 1 "Grand Teton / footprints 3428-3428 of 6105")
	)
	(layers
		(0 "F.Cu" signal "TOP")
		(4 "In1.Cu" signal "GND")
		(6 "In2.Cu" signal "IN1")
		(8 "In3.Cu" signal "GND1")
		(10 "In4.Cu" signal "IN2")
		(12 "In5.Cu" signal "GND2")
		(14 "In6.Cu" signal "IN3")
		(16 "In7.Cu" signal "GND3")
		(18 "In8.Cu" signal "VCC")
		(20 "In9.Cu" signal "VCC1")
		(22 "In10.Cu" signal "GND4")
		(24 "In11.Cu" signal "IN4")
		(26 "In12.Cu" signal "GND5")
		(28 "In13.Cu" signal "IN5")
		(30 "In14.Cu" signal "GND6")
		(32 "In15.Cu" signal "IN6")
		(34 "In16.Cu" signal "GND7")
		(2 "B.Cu" signal "BOTTOM")
		(9 "F.Adhes" user "F.Adhesive")
		(11 "B.Adhes" user "B.Adhesive")
		(13 "F.Paste" user "Package Geometry/Pastemask Top")
		(15 "B.Paste" user "Package Geometry/Pastemask Bottom")
		(5 "F.SilkS" user "Ref Des/Silkscreen Top")
		(7 "B.SilkS" user "Ref Des/Silkscreen Bottom")
		(1 "F.Mask" user "Board Geometry/Soldermask Top")
		(3 "B.Mask" user "Board Geometry/Soldermask Bottom")
		(17 "Dwgs.User" user "User.Drawings")
		(19 "Cmts.User" user "User.Comments")
		(21 "Eco1.User" user "User.Eco1")
		(23 "Eco2.User" user "User.Eco2")
		(25 "Edge.Cuts" user "Board Geometry/Outline")
		(27 "Margin" user)
		(31 "F.CrtYd" user "Package Geometry/Place Bound Top")
		(29 "B.CrtYd" user "Package Geometry/Place Bound Bottom")
		(35 "F.Fab" user "Ref Des/Assembly Top")
		(33 "B.Fab" user "Ref Des/Assembly Bottom")
	)
	(footprint ""
		(layer "F.Cu")
		(at 250.65482 2.921 180)
		(property "Reference" "J85"
			(at -4.26085 -1.143 90)
			(unlocked yes)
			(layer "F.SilkS")
			(effects
				(font
					(size 0.7874 0.5842)
					(thickness 0.1524)
				)
				(justify left)
			)
		)
		(property "Value" ""
			(at 0 0 180)
			(layer "F.Fab")
			(effects
				(font
					(size 1.27 1.27)
				)
			)
		)
		(duplicate_pad_numbers_are_jumpers no)
		(fp_line
			(start 1.2192 2.1082)
			(end -1.2192 2.1082)
			(stroke
				(width 0.1524)
				(type default)
			)
			(layer "F.SilkS")
		)
		(fp_line
			(start 1.2192 -2.1082)
			(end 1.2192 2.1082)
			(stroke
				(width 0.1524)
				(type default)
			)
			(layer "F.SilkS")
		)
		(fp_line
			(start -1.2192 2.1082)
			(end -1.2192 -2.1082)
			(stroke
				(width 0.1524)
				(type default)
			)
			(layer "F.SilkS")
		)
		(fp_line
			(start -1.2192 -2.1082)
			(end 1.2192 -2.1082)
			(stroke
				(width 0.1524)
				(type default)
			)
			(layer "F.SilkS")
		)
		(pad "" np_thru_hole circle
			(at -2.8829 -1.27 90)
			(size 1.0414 1.0414)
			(drill 1.0414)
			(layers "*.Cu" "*.Mask")
			(clearance 0.381)
			(thermal_gap 0.381)
		)
		(pad "" np_thru_hole circle
			(at -2.8829 1.27 90)
			(size 1.0414 1.0414)
			(drill 1.0414)
			(layers "*.Cu" "*.Mask")
			(clearance 0.381)
			(thermal_gap 0.381)
		)
		(pad "" np_thru_hole circle
			(at 3.4671 -1.27 90)
			(size 1.0414 1.0414)
			(drill 1.0414)
			(layers "*.Cu" "*.Mask")
			(clearance 0.381)
			(thermal_gap 0.381)
		)
		(pad "" np_thru_hole circle
			(at 3.4671 1.27 90)
			(size 1.0414 1.0414)
			(drill 1.0414)
			(layers "*.Cu" "*.Mask")
			(clearance 0.381)
			(thermal_gap 0.381)
		)
		(pad "1" smd rect
			(at 0.8255 -0.249936 90)
			(size 0.3048 0.508)
			(layers "F.Cu" "F.Mask" "F.Paste")
			(net "DELTA_L_85_10INCH_IN3_DN")
		)
		(pad "2" smd rect
			(at 0.8255 0.249936 90)
			(size 0.3048 0.508)
			(layers "F.Cu" "F.Mask" "F.Paste")
			(net "DELTA_L_85_10INCH_IN3_DP")
		)
		(pad "3" smd circle
			(at 0 0 180)
			(size 0 0)
			(layers "F.Cu" "F.Mask" "F.Paste")
			(net "DELTA_L_GND_1")
		)
		(zone
			(layer "F.Cu")
			(hatch none 0.5)
			(connect_pads
				(clearance 0)
			)
			(min_thickness 0.25)
			(keepout
				(tracks not_allowed)
				(vias allowed)
				(pads allowed)
				(copperpour not_allowed)
				(footprints allowed)
			)
			(placement
				(enabled no)
				(sheetname "")
			)
			(fill
				(thermal_gap 0.5)
				(thermal_bridge_width 0.5)
				(island_removal_mode 0)
			)
			(polygon
				(pts
					(xy 249.53722 3.46964) (xy 249.53722 3.374136) (xy 250.13412 3.374136) (xy 250.13412 2.967736)
					(xy 249.53722 2.967736) (xy 249.53722 2.874264) (xy 250.13412 2.874264) (xy 250.13412 2.467864)
					(xy 249.53722 2.467864) (xy 249.53722 2.37236) (xy 250.23572 2.37236) (xy 250.23572 3.46964)
				)
			)
		)
		(zone
			(layers "F.Cu" "B.Cu" "In1.Cu" "In2.Cu" "In3.Cu" "In4.Cu" "In5.Cu" "In6.Cu"
				"In7.Cu" "In8.Cu" "In9.Cu" "In10.Cu" "In11.Cu" "In12.Cu" "In13.Cu" "In14.Cu"
				"In15.Cu" "In16.Cu"
			)
			(hatch none 0.5)
			(connect_pads
				(clearance 0)
			)
			(min_thickness 0.25)
			(keepout
				(tracks not_allowed)
				(vias allowed)
				(pads allowed)
				(copperpour not_allowed)
				(footprints allowed)
			)
			(placement
				(enabled no)
				(sheetname "")
			)
			(fill
				(thermal_gap 0.5)
				(thermal_bridge_width 0.5)
				(island_removal_mode 0)
			)
			(polygon
				(pts
					(arc
						(start 248.11482 1.651)
						(mid 246.26062 1.651)
						(end 248.11482 1.651)
					)
				)
			)
		)
		(zone
			(layers "F.Cu" "B.Cu" "In1.Cu" "In2.Cu" "In3.Cu" "In4.Cu" "In5.Cu" "In6.Cu"
				"In7.Cu" "In8.Cu" "In9.Cu" "In10.Cu" "In11.Cu" "In12.Cu" "In13.Cu" "In14.Cu"
				"In15.Cu" "In16.Cu"
			)
			(hatch none 0.5)
			(connect_pads
				(clearance 0)
			)
			(min_thickness 0.25)
			(keepout
				(tracks not_allowed)
				(vias allowed)
				(pads allowed)
				(copperpour not_allowed)
				(footprints allowed)
			)
			(placement
				(enabled no)
				(sheetname "")
			)
			(fill
				(thermal_gap 0.5)
				(thermal_bridge_width 0.5)
				(island_removal_mode 0)
			)
			(polygon
				(pts
					(arc
						(start 248.11482 4.191)
						(mid 246.26062 4.191)
						(end 248.11482 4.191)
					)
				)
			)
		)
		(zone
			(layers "F.Cu" "B.Cu" "In1.Cu" "In2.Cu" "In3.Cu" "In4.Cu" "In5.Cu" "In6.Cu"
				"In7.Cu" "In8.Cu" "In9.Cu" "In10.Cu" "In11.Cu" "In12.Cu" "In13.Cu" "In14.Cu"
				"In15.Cu" "In16.Cu"
			)
			(hatch none 0.5)
			(connect_pads
				(clearance 0)
			)
			(min_thickness 0.25)
			(keepout
				(tracks not_allowed)
				(vias allowed)
				(pads allowed)
				(copperpour not_allowed)
				(footprints allowed)
			)
			(placement
				(enabled no)
				(sheetname "")
			)
			(fill
				(thermal_gap 0.5)
				(thermal_bridge_width 0.5)
				(island_removal_mode 0)
			)
			(polygon
				(pts
					(arc
						(start 254.46482 1.651)
						(mid 252.61062 1.651)
						(end 254.46482 1.651)
					)
				)
			)
		)
		(zone
			(layers "F.Cu" "B.Cu" "In1.Cu" "In2.Cu" "In3.Cu" "In4.Cu" "In5.Cu" "In6.Cu"
				"In7.Cu" "In8.Cu" "In9.Cu" "In10.Cu" "In11.Cu" "In12.Cu" "In13.Cu" "In14.Cu"
				"In15.Cu" "In16.Cu"
			)
			(hatch none 0.5)
			(connect_pads
				(clearance 0)
			)
			(min_thickness 0.25)
			(keepout
				(tracks not_allowed)
				(vias allowed)
				(pads allowed)
				(copperpour not_allowed)
				(footprints allowed)
			)
			(placement
				(enabled no)
				(sheetname "")
			)
			(fill
				(thermal_gap 0.5)
				(thermal_bridge_width 0.5)
				(island_removal_mode 0)
			)
			(polygon
				(pts
					(arc
						(start 254.46482 4.191)
						(mid 252.61062 4.191)
						(end 254.46482 4.191)
					)
				)
			)
		)
	)
)
